(kicad_pcb
	(version 20241229)
	(generator "pcbnew")
	(generator_version "9.0")
	(general
		(thickness 1.62)
		(legacy_teardrops no)
	)
	(paper "A3")
	(title_block
		(title "COM Express 7 Baseboard")
		(date "2025-02-04")
		(rev "1.1.2")
		(company "Antmicro Ltd")
		(comment 1 "www.antmicro.com")
		(comment 9 "footprints 487-488 of 802")
	)
	(layers
		(0 "F.Cu" signal)
		(4 "In1.Cu" signal)
		(6 "In2.Cu" signal)
		(8 "In3.Cu" signal)
		(10 "In4.Cu" signal)
		(12 "In5.Cu" signal)
		(14 "In6.Cu" signal)
		(2 "B.Cu" signal)
		(9 "F.Adhes" user "F.Adhesive")
		(11 "B.Adhes" user "B.Adhesive")
		(13 "F.Paste" user)
		(15 "B.Paste" user)
		(5 "F.SilkS" user "F.Silkscreen")
		(7 "B.SilkS" user "B.Silkscreen")
		(1 "F.Mask" user)
		(3 "B.Mask" user)
		(17 "Dwgs.User" user "User.Drawings")
		(19 "Cmts.User" user "User.Comments")
		(21 "Eco1.User" user "User.Eco1")
		(23 "Eco2.User" user "User.Eco2")
		(25 "Edge.Cuts" user)
		(27 "Margin" user)
		(31 "F.CrtYd" user "F.Courtyard")
		(29 "B.CrtYd" user "B.Courtyard")
		(35 "F.Fab" user)
		(33 "B.Fab" user)
	)
	(footprint "antmicro-footprints:R_0402_1005Metric"
		(layer "F.Cu")
		(at 122.05 86.06)
		(descr "Resistor SMD 0402")
		(tags "resistor SMD 0402")
		(property "Reference" "R24"
			(at 0.75 0.4 0)
			(layer "F.SilkS")
			(effects
				(font
					(size 0.7 0.7)
					(thickness 0.15)
				)
				(justify left bottom)
			)
		)
		(property "Value" "R_10k_0402"
			(at -1.011843 1.772047 0)
			(layer "F.Fab")
			(effects
				(font
					(size 0.7 0.7)
					(thickness 0.15)
				)
				(justify left bottom)
			)
		)
		(property "Datasheet" "https://www.bourns.com/docs/product-datasheets/cr.pdf"
			(at 0 0 0)
			(layer "F.Fab")
			(hide yes)
			(effects
				(font
					(size 1.27 1.27)
					(thickness 0.15)
				)
			)
		)
		(property "Author" "Antmicro"
			(at 0 0 0)
			(layer "F.Fab")
			(hide yes)
			(effects
				(font
					(size 1 1)
					(thickness 0.15)
				)
			)
		)
		(property "License" "Apache-2.0"
			(at 0 0 0)
			(layer "F.Fab")
			(hide yes)
			(effects
				(font
					(size 1 1)
					(thickness 0.15)
				)
			)
		)
		(property "MPN" "CR0402-FX-1002GLF"
			(at 0 0 0)
			(layer "F.Fab")
			(hide yes)
			(effects
				(font
					(size 1 1)
					(thickness 0.15)
				)
			)
		)
		(property "Manufacturer" "Bourns"
			(at 0 0 0)
			(layer "F.Fab")
			(hide yes)
			(effects
				(font
					(size 1 1)
					(thickness 0.15)
				)
			)
		)
		(property "Public" "False"
			(at 0 0 0)
			(layer "F.Fab")
			(hide yes)
			(effects
				(font
					(size 1 1)
					(thickness 0.15)
				)
			)
		)
		(property "Tolerance" "1%"
			(at 0 0 0)
			(layer "F.Fab")
			(hide yes)
			(effects
				(font
					(size 1 1)
					(thickness 0.15)
				)
			)
		)
		(property "Val" "10k"
			(at 0 0 0)
			(layer "F.Fab")
			(hide yes)
			(effects
				(font
					(size 1 1)
					(thickness 0.15)
				)
			)
		)
		(sheetname "2xUSB3.0+RJ45")
		(sheetfile "usb3+rj45.kicad_sch")
		(attr smd)
		(fp_rect
			(start -0.925 -0.47)
			(end 0.925 0.47)
			(stroke
				(width 0.05)
				(type default)
			)
			(fill no)
			(layer "F.CrtYd")
		)
		(fp_rect
			(start -0.5 -0.25)
			(end 0.5 0.25)
			(stroke
				(width 0.15)
				(type solid)
			)
			(fill no)
			(layer "F.Fab")
		)
		(pad "1" smd roundrect
			(at -0.48 0)
			(size 0.59 0.64)
			(layers "F.Cu" "F.Mask" "F.Paste")
			(roundrect_rratio 0.25)
			(net 555 "/2xUSB3.0+RJ45/EN_1B")
			(pintype "passive")
			(teardrops
				(best_length_ratio 0.2)
				(max_length 1)
				(best_width_ratio 0.9)
				(max_width 2)
				(curved_edges yes)
				(filter_ratio 0.9)
				(enabled yes)
				(allow_two_segments yes)
				(prefer_zone_connections yes)
			)
		)
		(pad "2" smd roundrect
			(at 0.48 0)
			(size 0.59 0.64)
			(layers "F.Cu" "F.Mask" "F.Paste")
			(roundrect_rratio 0.25)
			(net 2 "+3V3")
			(pintype "passive")
			(teardrops
				(best_length_ratio 0.2)
				(max_length 1)
				(best_width_ratio 0.9)
				(max_width 2)
				(curved_edges yes)
				(filter_ratio 0.9)
				(enabled yes)
				(allow_two_segments yes)
				(prefer_zone_connections yes)
			)
		)
	)
	(footprint "antmicro-footprints:TP_SMD_0.75mm"
		(layer "F.Cu")
		(at 196.8 133 45)
		(property "Reference" "TP54"
			(at 0.4 0.45 45)
			(layer "F.SilkS")
			(effects
				(font
					(size 0.7 0.7)
					(thickness 0.15)
				)
				(justify left bottom)
			)
		)
		(property "Value" "TP_0.75mm_SMD"
			(at 0 1.2 45)
			(layer "F.Fab")
			(effects
				(font
					(size 0.7 0.7)
					(thickness 0.15)
				)
				(justify left bottom)
			)
		)
		(property "Author" "Antmicro"
			(at 369.6 -271.22 45)
			(layer "F.Fab")
			(hide yes)
			(effects
				(font
					(size 1 1)
					(thickness 0.15)
				)
			)
		)
		(property "License" "Apache-2.0"
			(at 369.6 -271.22 45)
			(layer "F.Fab")
			(hide yes)
			(effects
				(font
					(size 1 1)
					(thickness 0.15)
				)
			)
		)
		(property "MPN" ""
			(at 369.6 -271.22 45)
			(layer "F.Fab")
			(hide yes)
			(effects
				(font
					(size 1 1)
					(thickness 0.15)
				)
			)
		)
		(property "Manufacturer" ""
			(at 369.6 -271.22 45)
			(layer "F.Fab")
			(hide yes)
			(effects
				(font
					(size 1 1)
					(thickness 0.15)
				)
			)
		)
		(property "Public" "False"
			(at 369.6 -271.22 45)
			(layer "F.Fab")
			(hide yes)
			(effects
				(font
					(size 1 1)
					(thickness 0.15)
				)
			)
		)
		(sheetname "PCIe redriver")
		(sheetfile "pcie_redriver.kicad_sch")
		(attr exclude_from_pos_files exclude_from_bom)
		(fp_circle
			(center 0 0)
			(end 0.475 0)
			(stroke
				(width 0.05)
				(type default)
			)
			(fill no)
			(layer "F.CrtYd")
		)
		(pad "1" smd circle
			(at 0 0 45)
			(size 0.75 0.75)
			(layers "F.Cu" "F.Mask")
			(net 717 "Net-(U40-SCL)")
			(pinfunction "1")
			(pintype "passive")
			(teardrops
				(best_length_ratio 0.4)
				(max_length 1)
				(best_width_ratio 0.9)
				(max_width 2)
				(curved_edges yes)
				(filter_ratio 0.9)
				(enabled yes)
				(allow_two_segments yes)
				(prefer_zone_connections yes)
			)
		)
	)
)
